;LEADER: 12 
;HEADER: 
;CODE  : ASCII 
;FILE  : 9332_F0TG_MB_C_V02_0417_0820-bd-18-6.drl for backdrilling ... from layer BOTTOM to layer GND2
;DESIGN: 9332_F0TG_MB_C_V02_0417_0820.brd
;MUST-NOT-CUT-LAYER = IN2,  MAX_DRILL_DEPTH = 72.65 MILS,  MFG_STUB_LENGTH = 0.00 MILS
;   BackdrillSize 1. = 14.800000 Tolerance = +0.000000/-0.000000 NON_PLATED MILS Quantity = 1000
;   BackdrillSize 2. = 17.000000 Tolerance = +0.000000/-0.000000 NON_PLATED MILS Quantity = 818
%
G90
X0624484Y1533336
X0619760Y1533336
X0615035Y1533336
R02X-0004724
X0600862Y1533336
X0596138Y1533336
X0591413Y1533336
X0586689Y1533336
X0652831Y1533336
X0648106Y1533336
X0643382Y1533336
X0638657Y1533336
X0633933Y1533336
X0629209Y1533336
X0581965Y1533336
X0622909Y1530608
R02X-0004724
X0608736Y1530608
X0604012Y1530608
X0599287Y1530608
R02X-0004724
X0585114Y1530608
X0651256Y1530608
X0646532Y1530608
X0641807Y1530608
X0637083Y1530608
X0632358Y1530608
X0627634Y1530608
X0580390Y1530608
X1632358Y1566336
X1627634Y1566336
X1622909Y1566336
R02X-0004724
X1608736Y1566336
X1604012Y1566336
X1599287Y1566336
X1594563Y1566336
X1660705Y1566336
X1655980Y1566336
X1651256Y1566336
X1646531Y1566336
X1641807Y1566336
X1637083Y1566336
X1589839Y1566336
X1630783Y1563608
R02X-0004724
X1616610Y1563608
X1611886Y1563608
X1607161Y1563608
R02X-0004724
X1592988Y1563608
X1659130Y1563608
X1654406Y1563608
X1649681Y1563608
X1644957Y1563608
X1640232Y1563608
X1635508Y1563608
X1588264Y1563608
X1240122Y1566336
X1235398Y1566336
X1230673Y1566336
R02X-0004724
X1216500Y1566336
X1211776Y1566336
X1207051Y1566336
X1202327Y1566336
X1268469Y1566336
X1263744Y1566336
X1259020Y1566336
X1254295Y1566336
X1249571Y1566336
X1244847Y1566336
X1197603Y1566336
X1238547Y1563608
R02X-0004724
X1224374Y1563608
X1219650Y1563608
X1214925Y1563608
R02X-0004724
X1200752Y1563608
X1266894Y1563608
X1262170Y1563608
X1257445Y1563608
X1252721Y1563608
X1247996Y1563608
X1243272Y1563608
X1196028Y1563608
X1475950Y1552698
X1439586Y1133292
X1471225Y1552698
X1430334Y1142858
X1466501Y1552698
X1430334Y1136480
X1472893Y1126914
X1532643Y1552698
X1527918Y1552698
X1472893Y1139669
X1523194Y1552698
X1472893Y1146047
X1518469Y1552698
X1472893Y1133292
X1474375Y1549970
X1435885Y1133292
X1469651Y1549970
X1426633Y1142858
X1464926Y1549970
X1426633Y1136480
X1469192Y1126914
X1531068Y1549970
X1526344Y1549970
X1469192Y1139669
X1521619Y1549970
X1469192Y1146047
X1516895Y1549970
X1469192Y1133292
X0496422Y1519698
X0485649Y1133293
X0491698Y1519698
X0474546Y1139670
X0486973Y1519698
X0474546Y1146048
X0482249Y1519698
X0474546Y1133293
X0477525Y1519698
X0463444Y1139670
X0472800Y1519698
X0463444Y1146048
X0468076Y1519698
X0463444Y1133293
X0463351Y1519698
X0454192Y1142859
X0458627Y1519698
X0454192Y1136481
X0524769Y1519698
X0496751Y1126915
X0520044Y1519698
X0496751Y1139670
X0515320Y1519698
X0496751Y1146048
X0510595Y1519698
X0496751Y1133293
X0505871Y1519698
X0485649Y1139670
X0501147Y1519698
X0485649Y1146048
X0453903Y1519698
X0454192Y1130103
X0494847Y1516970
X0481948Y1133293
X0490123Y1516970
X0470845Y1139670
X0485399Y1516970
X0470845Y1146048
X0480674Y1516970
X0470845Y1133293
X0475950Y1516970
X0459743Y1139670
X0471225Y1516970
X0459743Y1146048
X0466501Y1516970
X0459743Y1133293
X0461777Y1516970
X0450491Y1142859
X0457052Y1516970
X0450491Y1136481
X0523194Y1516970
X0493050Y1126915
X0518470Y1516970
X0493050Y1139670
X0513745Y1516970
X0493050Y1146048
X0509021Y1516970
X0493050Y1133293
X0504296Y1516970
X0481948Y1139670
X0499572Y1516970
X0481948Y1146048
X0452328Y1516970
X0450491Y1130103
X0407957Y1133293
X0407957Y1146048
X0407957Y1139670
X0396855Y1133293
X0396855Y1146048
X0396855Y1139670
X0385752Y1133293
X0385752Y1146048
X0385752Y1139670
X0428311Y1130103
R02Y0006378
X0419059Y1133293
X0419059Y1146048
X0419059Y1139670
X0385752Y1126915
X0411658Y1133293
X0411658Y1146048
X0411658Y1139670
X0400555Y1133293
X0400555Y1146048
X0400555Y1139670
X0389453Y1133293
X0389453Y1146048
X0389453Y1139670
X0432012Y1130103
R02Y0006378
X0422760Y1133293
X0422760Y1146048
X0422760Y1139670
X0389453Y1126915
X1494847Y1552698
X1450688Y1146047
X1490123Y1552698
X1450688Y1133292
X1485399Y1552698
X1439586Y1139669
X1480674Y1552698
X1439586Y1146047
X1493273Y1549970
X1446987Y1146047
X1488548Y1549970
X1446987Y1133292
X1483824Y1549970
X1435885Y1139669
X1479099Y1549970
X1435885Y1146047
X1384099Y1133292
X1384099Y1146047
X1384099Y1139669
X1372997Y1133292
X1372997Y1146047
X1372997Y1139669
X1361894Y1133292
X1361894Y1146047
X1361894Y1139669
X1404453Y1130102
R02Y0006378
X1395201Y1133292
X1395201Y1146047
X1395201Y1139669
X1361894Y1126914
X1387800Y1133292
X1387800Y1146047
X1387800Y1139669
X1376697Y1133292
X1376697Y1146047
X1376697Y1139669
X1365595Y1133292
X1365595Y1146047
X1365595Y1139669
X1408154Y1130102
R02Y0006378
X1398902Y1133292
X1398902Y1146047
X1398902Y1139669
X1365595Y1126914
X1449507Y0924268
X1449507Y0911512
X1449507Y0917890
X1460609Y0930646
X1460609Y0911512
X1460609Y0917890
X1460609Y0924268
X1471712Y0930646
X1471712Y0917890
X1429153Y0927457
R02Y-0006378
X1438405Y0924268
X1438405Y0911512
X1438405Y0917890
X1471712Y0924268
X1445806Y0924268
X1445806Y0911512
X1445806Y0917890
X1456909Y0930646
X1456909Y0911512
X1456909Y0917890
X1456909Y0924268
X1468011Y0930646
X1468011Y0917890
X1425452Y0927457
R02Y-0006378
X1434704Y0924268
X1434704Y0911512
X1434704Y0917890
X1468011Y0924268
X1504296Y1552698
X1461791Y1133292
X1499572Y1552698
X1450688Y1139669
X1513745Y1552698
X1461791Y1139669
X1509021Y1552698
X1461791Y1146047
X1502721Y1549970
X1458090Y1133292
X1497997Y1549970
X1446987Y1139669
X1512170Y1549970
X1458090Y1139669
X1507446Y1549970
X1458090Y1146047
X1460202Y1549970
X1426633Y1130102
X1461777Y1552698
X1430334Y1130102
X0524507Y1053568
X0518956Y1044001
X0524507Y1066324
X0517105Y1149237
X0517105Y1130103
X0517105Y1110970
R02Y-0019134
X0524507Y1142859
X0524507Y1123726
X0524507Y1104592
X0524507Y1085458
X0522657Y1069513
X0518956Y1146048
X0518956Y1126915
X0518956Y1107781
R02Y-0019134
X0522657Y1146048
X0522657Y1126915
X0522657Y1107781
X0522657Y1088647
X0518956Y1101403
X0524507Y1098214
X0517105Y1098214
X0522657Y1095025
X0518956Y1095025
X0524507Y1091836
X0517105Y1085458
X0524507Y1155615
X0522657Y1152426
X0522657Y1082269
X0518956Y1152426
X0524507Y1149237
X0517105Y1142859
X0522657Y1139670
X0518956Y1139670
X0524507Y1136481
X0517105Y1136481
X0522657Y1133293
X0518956Y1133293
X0524507Y1130103
X0518956Y1082269
X0517105Y1123726
X0522657Y1120537
X0518956Y1120537
X0524507Y1117348
X0517105Y1117348
X0522657Y1114159
X0518956Y1114159
X0524507Y1110970
X0517105Y1104592
X0522657Y1101403
X0524507Y1079080
X0522657Y1050379
X0517105Y1047190
X0517105Y1066324
X0522657Y1063135
X0518956Y1063135
X0524507Y1059946
X0517105Y1079080
X0522657Y1075891
X0518956Y1075891
X0524507Y1072702
X0524507Y1040812
X0517105Y1040812
X0518956Y1037623
X0522657Y1037623
X0524507Y1034434
X0517105Y1034434
X0518956Y1031245
X0518956Y1050379
X0517775Y1007183
X0517775Y0975293
X0517775Y0956159
R02Y-0019134
X0517775Y0898758
X0521475Y0968915
R03Y-0019134
X0521475Y0892380
X0515924Y0972104
R03Y-0019134
X0515924Y0895569
X0523326Y0972104
R03Y-0019134
X0523326Y0895569
X0515924Y0908325
X0521475Y0905135
X0517775Y0905135
X0523326Y0901947
X0515924Y0901947
X0521475Y0898758
X0517775Y0892380
X0517775Y0962537
X0523326Y0959348
X0523326Y0889191
X0515924Y0959348
X0521475Y0956159
X0517775Y0949781
X0523326Y0946592
X0515924Y0946592
X0521475Y0943403
X0517775Y0943403
X0523326Y0940214
X0515924Y0940214
X0521475Y0937025
X0515924Y0889191
X0517775Y0930647
X0523326Y0927458
X0515924Y0927458
X0521475Y0924269
X0517775Y0924269
X0523326Y0921080
X0515924Y0921080
X0521475Y0917891
X0517775Y0911513
X0523326Y0908325
X0521475Y0886002
X0515924Y0991238
X0521475Y0988049
X0517775Y0981671
X0523326Y0978482
X0515924Y0978482
X0521475Y0975293
X0517775Y0968915
X0523326Y0965726
X0515924Y0965726
X0521475Y0962537
X0515924Y1003994
X0523326Y1003994
X0521475Y1000805
X0517775Y1000805
X0515924Y0997616
X0523326Y0997616
X0521475Y0994427
X0517775Y0988049
X0521475Y1007183
X0523326Y1010372
X0515924Y0984860
X1500649Y1053567
X1495098Y1044000
X1500649Y1066323
X1493247Y1149236
X1493247Y1130102
X1493247Y1110969
R02Y-0019134
X1500649Y1142858
X1500649Y1123725
X1500649Y1104591
X1500649Y1085457
X1498799Y1069512
X1495098Y1146047
X1495098Y1126914
X1495098Y1107780
R02Y-0019134
X1498799Y1146047
X1498799Y1126914
X1498799Y1107780
X1498799Y1088646
X1495098Y1101402
X1500649Y1098213
X1493247Y1098213
X1498799Y1095024
X1495098Y1095024
X1500649Y1091835
X1493247Y1085457
X1500649Y1155614
X1498799Y1152425
X1498799Y1082268
X1495098Y1152425
X1500649Y1149236
X1493247Y1142858
X1498799Y1139669
X1495098Y1139669
X1500649Y1136480
X1493247Y1136480
X1498799Y1133292
X1495098Y1133292
X1500649Y1130102
X1495098Y1082268
X1493247Y1123725
X1498799Y1120536
X1495098Y1120536
X1500649Y1117347
X1493247Y1117347
X1498799Y1114158
X1495098Y1114158
X1500649Y1110969
X1493247Y1104591
X1498799Y1101402
X1500649Y1079079
X1498799Y1050378
X1493247Y1047189
X1493247Y1066323
X1498799Y1063134
X1495098Y1063134
X1500649Y1059945
X1493247Y1079079
X1498799Y1075890
X1495098Y1075890
X1500649Y1072701
X1500649Y1040811
X1493247Y1040811
X1495098Y1037622
X1498799Y1037622
X1500649Y1034433
X1493247Y1034433
X1495098Y1031244
X1495098Y1050378
X1493917Y1007182
X1493917Y0975292
X1493917Y0956158
R02Y-0019134
X1493917Y0898757
X1497617Y0968914
R03Y-0019134
X1497617Y0892379
X1492066Y0972103
R03Y-0019134
X1492066Y0895568
X1499468Y0972103
R03Y-0019134
X1499468Y0895568
X1492066Y0908324
X1497617Y0905134
X1493917Y0905134
X1499468Y0901946
X1492066Y0901946
X1497617Y0898757
X1493917Y0892379
X1493917Y0962536
X1499468Y0959347
X1499468Y0889190
X1492066Y0959347
X1497617Y0956158
X1493917Y0949780
X1499468Y0946591
X1492066Y0946591
X1497617Y0943402
X1493917Y0943402
X1499468Y0940213
X1492066Y0940213
X1497617Y0937024
X1492066Y0889190
X1493917Y0930646
X1499468Y0927457
X1492066Y0927457
X1497617Y0924268
X1493917Y0924268
X1499468Y0921079
X1492066Y0921079
X1497617Y0917890
X1493917Y0911512
X1499468Y0908324
X1497617Y0886001
X1492066Y0991237
X1497617Y0988048
X1493917Y0981670
X1499468Y0978481
X1492066Y0978481
X1497617Y0975292
X1493917Y0968914
X1499468Y0965725
X1492066Y0965725
X1497617Y0962536
X1492066Y1003993
X1499468Y1003993
X1497617Y1000804
X1493917Y1000804
X1492066Y0997615
X1499468Y0997615
X1497617Y0994426
X1493917Y0988048
X1497617Y1007182
X1499468Y1010371
X1492066Y0984859
X0357996Y1053568
X0359847Y1044001
X0357996Y1066324
X0365398Y1149237
X0365398Y1130103
X0365398Y1110970
R02Y-0019134
X0357996Y1142859
X0357996Y1123726
X0357996Y1104592
X0357996Y1085458
X0359847Y1069513
X0363547Y1146048
X0363547Y1126915
X0363547Y1107781
R02Y-0019134
X0359847Y1146048
X0359847Y1126915
X0359847Y1107781
X0359847Y1088647
X0363547Y1101403
X0357996Y1098214
X0365398Y1098214
X0359847Y1095025
X0363547Y1095025
X0357996Y1091836
X0365398Y1085458
X0357996Y1155615
X0359847Y1152426
X0359847Y1082269
X0363547Y1152426
X0357996Y1149237
X0365398Y1142859
X0359847Y1139670
X0363547Y1139670
X0357996Y1136481
X0365398Y1136481
X0359847Y1133293
X0363547Y1133293
X0357996Y1130103
X0363547Y1082269
X0365398Y1123726
X0359847Y1120537
X0363547Y1120537
X0357996Y1117348
X0365398Y1117348
X0359847Y1114159
X0363547Y1114159
X0357996Y1110970
X0365398Y1104592
X0359847Y1101403
X0357996Y1079080
X0359847Y1050379
X0365398Y1047190
X0365398Y1066324
X0359847Y1063135
X0363547Y1063135
X0357996Y1059946
X0365398Y1079080
X0359847Y1075891
X0363547Y1075891
X0357996Y1072702
X0357996Y1040812
X0365398Y1040812
X0363547Y1037623
X0359847Y1037623
X0357996Y1034434
X0365398Y1034434
X0363547Y1031245
X0363547Y1050379
X0362366Y1007183
X0362366Y0975293
X0362366Y0956159
R02Y-0019134
X0362366Y0898758
X0358665Y0968915
R03Y-0019134
X0358665Y0892380
X0364217Y0972104
R03Y-0019134
X0364217Y0895569
X0356815Y0972104
R03Y-0019134
X0356815Y0895569
X0364217Y0908325
X0358665Y0905135
X0362366Y0905135
X0356815Y0901947
X0364217Y0901947
X0358665Y0898758
X0362366Y0892380
X0362366Y0962537
X0356815Y0959348
X0356815Y0889191
X0364217Y0959348
X0358665Y0956159
X0362366Y0949781
X0356815Y0946592
X0364217Y0946592
X0358665Y0943403
X0362366Y0943403
X0356815Y0940214
X0364217Y0940214
X0358665Y0937025
X0364217Y0889191
X0362366Y0930647
X0356815Y0927458
X0364217Y0927458
X0358665Y0924269
X0362366Y0924269
X0356815Y0921080
X0364217Y0921080
X0358665Y0917891
X0362366Y0911513
X0356815Y0908325
X0358665Y0886002
X0362366Y0994427
X0356815Y0991238
X0362366Y0981671
X0356815Y0978482
X0364217Y0978482
X0358665Y0975293
X0362366Y0968915
X0356815Y0965726
X0364217Y0965726
X0358665Y0962537
X0364217Y1003994
X0356815Y1003994
X0358665Y1000805
X0362366Y1000805
X0364217Y0997616
X0356815Y0997616
X0358665Y0994427
X0362366Y0988049
X0358665Y1007183
X0356815Y1010372
X0364217Y0984860
X1334138Y1053567
X1335989Y1044000
X1334138Y1066323
X1341540Y1149236
X1341540Y1130102
X1341540Y1110969
R02Y-0019134
X1334138Y1142858
X1334138Y1123725
X1334138Y1104591
X1334138Y1085457
X1335989Y1069512
X1339689Y1146047
X1339689Y1126914
X1339689Y1107780
R02Y-0019134
X1335989Y1146047
X1335989Y1126914
X1335989Y1107780
X1335989Y1088646
X1339689Y1101402
X1334138Y1098213
X1341540Y1098213
X1335989Y1095024
X1339689Y1095024
X1334138Y1091835
X1341540Y1085457
X1334138Y1155614
X1335989Y1152425
X1335989Y1082268
X1339689Y1152425
X1334138Y1149236
X1341540Y1142858
X1335989Y1139669
X1339689Y1139669
X1334138Y1136480
X1341540Y1136480
X1335989Y1133292
X1339689Y1133292
X1334138Y1130102
X1339689Y1082268
X1341540Y1123725
X1335989Y1120536
X1339689Y1120536
X1334138Y1117347
X1341540Y1117347
X1335989Y1114158
X1339689Y1114158
X1334138Y1110969
X1341540Y1104591
X1335989Y1101402
X1334138Y1079079
X1335989Y1050378
X1341540Y1047189
X1341540Y1066323
X1335989Y1063134
X1339689Y1063134
X1334138Y1059945
X1341540Y1079079
X1335989Y1075890
X1339689Y1075890
X1334138Y1072701
X1334138Y1040811
X1341540Y1040811
X1339689Y1037622
X1335989Y1037622
X1334138Y1034433
X1341540Y1034433
X1339689Y1031244
X1339689Y1050378
X1338508Y1007182
X1338508Y0975292
X1338508Y0956158
R02Y-0019134
X1338508Y0898757
X1334807Y0968914
R03Y-0019134
X1334807Y0892379
X1340359Y0972103
R03Y-0019134
X1340359Y0895568
X1332957Y0972103
R03Y-0019134
X1332957Y0895568
X1340359Y0908324
X1334807Y0905134
X1338508Y0905134
X1332957Y0901946
X1340359Y0901946
X1334807Y0898757
X1338508Y0892379
X1338508Y0962536
X1332957Y0959347
X1332957Y0889190
X1340359Y0959347
X1334807Y0956158
X1338508Y0949780
X1332957Y0946591
X1340359Y0946591
X1334807Y0943402
X1338508Y0943402
X1332957Y0940213
X1340359Y0940213
X1334807Y0937024
X1340359Y0889190
X1338508Y0930646
X1332957Y0927457
X1340359Y0927457
X1334807Y0924268
X1338508Y0924268
X1332957Y0921079
X1340359Y0921079
X1334807Y0917890
X1338508Y0911512
X1332957Y0908324
X1334807Y0886001
X1338508Y0994426
X1332957Y0991237
X1338508Y0981670
X1332957Y0978481
X1340359Y0978481
X1334807Y0975292
X1338508Y0968914
X1332957Y0965725
X1340359Y0965725
X1334807Y0962536
X1340359Y1003993
X1332957Y1003993
X1334807Y1000804
X1338508Y1000804
X1340359Y0997615
X1332957Y0997615
X1334807Y0994426
X1338508Y0988048
X1334807Y1007182
X1332957Y1010371
X1340359Y0984859
X0484467Y0905135
X1371815Y0905134
X0473365Y0898758
X1382918Y0898757
X0473365Y0892380
X1382918Y0892379
X0473365Y0905135
X1382918Y0905134
X0462263Y0898758
X1394020Y0898757
X0462263Y0892380
X1394020Y0892379
X0462263Y0905135
X1394020Y0905134
X0453011Y0895569
X1403272Y0895568
X0453011Y0901947
X1403272Y0901946
X0495570Y0911513
X1360713Y0911512
X0495570Y0898758
X1360713Y0898757
X0495570Y0892380
X1360713Y0892379
X0495570Y0905135
X1360713Y0905134
X0484467Y0898758
X1371815Y0898757
X0484467Y0892380
X1371815Y0892379
X0453011Y0908325
X1403272Y0908324
X0480767Y0905135
X1375516Y0905134
X0469664Y0898758
X1386619Y0898757
X0469664Y0892380
X1386619Y0892379
X0469664Y0905135
X1386619Y0905134
X0458562Y0898758
X1397721Y0898757
X0458562Y0892380
X1397721Y0892379
X0458562Y0905135
X1397721Y0905134
X0449310Y0895569
X1406973Y0895568
X0449310Y0901947
X1406973Y0901946
X0491869Y0911513
X1364414Y0911512
X0491869Y0898758
X1364414Y0898757
X0491869Y0892380
X1364414Y0892379
X0491869Y0905135
X1364414Y0905134
X0480767Y0898758
X1375516Y0898757
X0480767Y0892380
X1375516Y0892379
X0449310Y0908325
X1406973Y0908324
X0406776Y0924269
X0406776Y0911513
X0406776Y0917891
X0395673Y0930647
X0395673Y0911513
X0395673Y0917891
X0395673Y0924269
X0384571Y0930647
X0384571Y0917891
X0427130Y0927458
R02Y-0006378
X0417878Y0924269
X0417878Y0911513
X0417878Y0917891
X0384571Y0924269
X0410477Y0924269
X0410477Y0911513
X0410477Y0917891
X0399374Y0930647
X0399374Y0911513
X0399374Y0917891
X0399374Y0924269
X0388272Y0930647
X0388272Y0917891
X0430831Y0927458
R02Y-0006378
X0421579Y0924269
X0421579Y0911513
X0421579Y0917891
X0388272Y0924269
M00
X0564279Y1592380
R08X-0012060
X0636639Y1592380
R05X-0012060
X0455739Y1592380
X0560879Y1592380
X0548819Y1592380
R07X-0012060
X0633239Y1592380
R05X-0012060
X0452339Y1592380
X1572153Y1625380
R08X-0012060
X1644513Y1625380
R05X-0012060
X1463613Y1625380
X1568753Y1625380
X1556693Y1625380
R07X-0012060
X1641113Y1625380
R05X-0012060
X1460213Y1625380
X1307979Y1625380
X1295919Y1625380
R07X-0012060
X1380339Y1625380
R05X-0012060
X1199439Y1625380
X1304579Y1625380
X1292519Y1625380
R07X-0012060
X1376939Y1625380
R05X-0012060
X1196039Y1625380
X1729557Y-0025912
X1539134Y-0025912
X1729557Y-0022512
X1539134Y-0022512
X1177404Y0021689
X0842320Y0021689
X1177404Y0018289
X0842320Y0018289
X0814296Y1387445
X0814296Y1384045
X0357713Y1452895
X0351013Y1462595
X0344313Y1472295
X0330913Y1452895
X0324213Y1462595
X0317513Y1472295
X0304113Y1452895
X0297413Y1462595
X0291175Y1480190
X0408683Y1494082
X0408683Y1484082
X0397913Y1452895
X0384513Y1452895
X0377813Y1462595
X0371113Y1472295
X0291175Y1505390
X0361113Y1452895
X0354413Y1462595
X0347713Y1472295
X0334313Y1452895
X0327613Y1462595
X0320913Y1472295
X0307513Y1452895
X0300813Y1462595
X0291175Y1483590
X0408683Y1497482
X0408683Y1480682
X0401313Y1452895
X0387913Y1452895
X0381213Y1462595
X0374513Y1472295
X0291175Y1501990
X1365586Y1485895
X1358886Y1495595
X1352186Y1505295
X1338786Y1485895
X1332086Y1495595
X1325386Y1505295
X1311986Y1485895
X1305286Y1495595
X1299048Y1513190
X1416556Y1527082
X1416556Y1517082
X1405786Y1485895
X1392386Y1485895
X1385686Y1495595
X1378986Y1505295
X1299048Y1538390
X1368986Y1485895
X1362286Y1495595
X1355586Y1505295
X1342186Y1485895
X1335486Y1495595
X1328786Y1505295
X1315386Y1485895
X1308686Y1495595
X1299048Y1516590
X1416556Y1530482
X1416556Y1513682
X1409186Y1485895
X1395786Y1485895
X1389086Y1495595
X1382386Y1505295
X1299048Y1534990
X1604962Y0069343
X1615966Y0075340
X1626962Y0069343
X1639170Y0075340
X1650170Y0069340
X1661166Y0075343
X1672170Y0069340
X1683304Y0075340
X1694300Y0069343
X1538966Y0069340
X1549962Y0075343
X1560966Y0069340
X1571966Y0075340
X1582966Y0069340
X1593966Y0075340
X1705304Y0075340
X1601562Y0069343
X1612566Y0075340
X1623562Y0069343
X1635770Y0075340
X1646770Y0069340
X1657766Y0075343
X1668770Y0069340
X1679904Y0075340
X1690900Y0069343
X1535566Y0069340
X1546562Y0075343
X1557566Y0069340
X1568566Y0075340
X1579566Y0069340
X1590566Y0075340
X1701904Y0075340
X0752599Y1064706
X0736457Y1051320
X0752599Y1084785
X0736457Y1238722
R04Y-0036811
X0752599Y1232029
R03Y-0036811
X0752599Y1088131
X0736457Y1235375
R04Y-0036811
X0752599Y1235375
R03Y-0036811
X0752599Y1151714
X0752599Y1145021
X0736457Y1141675
X0736457Y1134982
X0752599Y1138328
X0752599Y1131635
X0736457Y1118249
X0736457Y1252108
X0736457Y1245415
X0736457Y1111556
X0752599Y1248761
X0752599Y1242068
X0736457Y1228682
X0736457Y1221989
X0752599Y1225336
X0752599Y1218643
X0736457Y1215297
X0736457Y1208604
X0752599Y1211950
X0752599Y1205257
X0752599Y1114903
X0736457Y1191871
X0736457Y1185178
X0752599Y1188525
X0752599Y1181832
X0736457Y1178486
X0736457Y1171793
X0752599Y1175139
X0752599Y1168446
X0736457Y1155060
X0736457Y1148367
X0752599Y1108210
X0736457Y1058013
X0752599Y1054667
X0736457Y1081438
X0736457Y1074745
X0752599Y1078092
X0752599Y1071399
X0736457Y1104863
X0736457Y1098171
X0752599Y1101517
X0752599Y1094824
X0752599Y1047974
X0736457Y1044627
X0752599Y1041281
X0736457Y1037934
X0752599Y1034588
X0736457Y1031241
X0752599Y1027895
X0752599Y1061360
X0752599Y1001123
X0736457Y0944234
X0736457Y0907423
X0736457Y0870611
R02Y-0036811
X0752599Y0937541
R04Y-0036811
X0736457Y0940887
R04Y-0036811
X0752599Y0940887
R04Y-0036811
X0752599Y0820415
X0752599Y0813722
X0736457Y0810375
X0736457Y0803682
X0752599Y0807029
X0752599Y0800336
X0736457Y0786950
X0736457Y0920808
X0736457Y0914115
X0736457Y0780257
X0752599Y0917462
X0752599Y0910769
X0736457Y0897383
X0736457Y0890690
X0752599Y0894037
X0752599Y0887344
X0736457Y0883997
X0736457Y0877304
X0752599Y0880651
X0752599Y0873958
X0752599Y0783604
X0736457Y0860572
X0736457Y0853879
X0752599Y0857226
X0752599Y0850533
X0736457Y0847186
X0736457Y0840493
X0752599Y0843840
X0752599Y0837147
X0736457Y0823761
X0736457Y0817068
X0752599Y0776911
X0736457Y0971005
X0752599Y0967659
X0736457Y0957619
X0736457Y0950926
X0752599Y0954273
X0752599Y0947580
X0736457Y0934194
X0736457Y0927501
X0752599Y0930848
X0752599Y0924155
X0752599Y0994430
X0736457Y0991084
X0752599Y0987737
X0736457Y0984391
X0752599Y0981045
X0736457Y0977698
X0752599Y0974352
X0736457Y0964312
X0736457Y0997777
X0736457Y1001123
X1728741Y1064705
X1712599Y1051319
X1728741Y1084784
X1712599Y1238721
R04Y-0036811
X1728741Y1232028
R03Y-0036811
X1728741Y1088130
X1712599Y1235374
R04Y-0036811
X1728741Y1235374
R03Y-0036811
X1728741Y1151713
X1728741Y1145020
X1712599Y1141674
X1712599Y1134981
X1728741Y1138327
X1728741Y1131634
X1712599Y1118248
X1712599Y1252107
X1712599Y1245414
X1712599Y1111555
X1728741Y1248760
X1728741Y1242067
X1712599Y1228681
X1712599Y1221988
X1728741Y1225335
X1728741Y1218642
X1712599Y1215296
X1712599Y1208603
X1728741Y1211949
X1728741Y1205256
X1728741Y1114902
X1712599Y1191870
X1712599Y1185177
X1728741Y1188524
X1728741Y1181831
X1712599Y1178485
X1712599Y1171792
X1728741Y1175138
X1728741Y1168445
X1712599Y1155059
X1712599Y1148366
X1728741Y1108209
X1712599Y1058012
X1728741Y1054666
X1712599Y1081437
X1712599Y1074744
X1728741Y1078091
X1728741Y1071398
X1712599Y1104862
X1712599Y1098170
X1728741Y1101516
X1728741Y1094823
X1728741Y1047973
X1712599Y1044626
X1728741Y1041280
X1712599Y1037933
X1728741Y1034587
X1712599Y1031240
X1728741Y1027894
X1728741Y1061359
X1728741Y1001122
X1712599Y0944233
X1712599Y0907422
X1712599Y0870610
R02Y-0036811
X1728741Y0937540
R04Y-0036811
X1712599Y0940886
R04Y-0036811
X1728741Y0940886
R04Y-0036811
X1728741Y0820414
X1728741Y0813721
X1712599Y0810374
X1712599Y0803681
X1728741Y0807028
X1728741Y0800335
X1712599Y0786949
X1712599Y0920807
X1712599Y0914114
X1712599Y0780256
X1728741Y0917461
X1728741Y0910768
X1712599Y0897382
X1712599Y0890689
X1728741Y0894036
X1728741Y0887343
X1712599Y0883996
X1712599Y0877303
X1728741Y0880650
X1728741Y0873957
X1728741Y0783603
X1712599Y0860571
X1712599Y0853878
X1728741Y0857225
X1728741Y0850532
X1712599Y0847185
X1712599Y0840492
X1728741Y0843839
X1728741Y0837146
X1712599Y0823760
X1712599Y0817067
X1728741Y0776910
X1712599Y0971004
X1728741Y0967658
X1712599Y0957618
X1712599Y0950925
X1728741Y0954272
X1728741Y0947579
X1712599Y0934193
X1712599Y0927500
X1728741Y0930847
X1728741Y0924154
X1728741Y0994429
X1712599Y0991083
X1728741Y0987736
X1712599Y0984390
X1728741Y0981044
X1712599Y0977697
X1728741Y0974351
X1712599Y0964311
X1712599Y0997776
X1712599Y1001122
X0144866Y1064706
X0128724Y1051320
X0144866Y1084785
X0128724Y1238722
R04Y-0036811
X0144866Y1232029
R03Y-0036811
X0144866Y1088131
X0128724Y1235375
R04Y-0036811
X0144866Y1235375
R03Y-0036811
X0144866Y1151714
X0144866Y1145021
X0128724Y1141675
X0128724Y1134982
X0144866Y1138328
X0144866Y1131635
X0128724Y1118249
X0128724Y1252108
X0128724Y1245415
X0128724Y1111556
X0144866Y1248761
X0144866Y1242068
X0128724Y1228682
X0128724Y1221989
X0144866Y1225336
X0144866Y1218643
X0128724Y1215297
X0128724Y1208604
X0144866Y1211950
X0144866Y1205257
X0144866Y1114903
X0128724Y1191871
X0128724Y1185178
X0144866Y1188525
X0144866Y1181832
X0128724Y1178486
X0128724Y1171793
X0144866Y1175139
X0144866Y1168446
X0128724Y1155060
X0128724Y1148367
X0144866Y1108210
X0128724Y1058013
X0144866Y1054667
X0128724Y1081438
X0128724Y1074745
X0144866Y1078092
X0144866Y1071399
X0128724Y1104863
X0128724Y1098171
X0144866Y1101517
X0144866Y1094824
X0144866Y1047974
X0128724Y1044627
X0144866Y1041281
X0128724Y1037934
X0144866Y1034588
X0128724Y1031241
X0144866Y1027895
X0144866Y1061360
X0144866Y1001123
X0128724Y0944234
X0128724Y0907423
X0128724Y0870611
R02Y-0036811
X0144866Y0937541
R04Y-0036811
X0128724Y0940887
R04Y-0036811
X0144866Y0940887
R04Y-0036811
X0144866Y0820415
X0144866Y0813722
X0128724Y0810375
X0128724Y0803682
X0144866Y0807029
X0144866Y0800336
X0128724Y0786950
X0128724Y0920808
X0128724Y0914115
X0128724Y0780257
X0144866Y0917462
X0144866Y0910769
X0128724Y0897383
X0128724Y0890690
X0144866Y0894037
X0144866Y0887344
X0128724Y0883997
X0128724Y0877304
X0144866Y0880651
X0144866Y0873958
X0144866Y0783604
X0128724Y0860572
X0128724Y0853879
X0144866Y0857226
X0144866Y0850533
X0128724Y0847186
X0128724Y0840493
X0144866Y0843840
X0144866Y0837147
X0128724Y0823761
X0128724Y0817068
X0144866Y0776911
X0128724Y0971005
X0144866Y0967659
X0128724Y0957619
X0128724Y0950926
X0144866Y0954273
X0144866Y0947580
X0128724Y0934194
X0128724Y0927501
X0144866Y0930848
X0144866Y0924155
X0144866Y0994430
X0128724Y0991084
X0144866Y0987737
X0128724Y0984391
X0144866Y0981045
X0128724Y0977698
X0144866Y0974352
X0128724Y0964312
X0128724Y0997777
X0128724Y1001123
X1121008Y1064705
X1104866Y1051319
X1121008Y1084784
X1104866Y1238721
R04Y-0036811
X1121008Y1232028
R03Y-0036811
X1121008Y1088130
X1104866Y1235374
R04Y-0036811
X1121008Y1235374
R03Y-0036811
X1121008Y1151713
X1121008Y1145020
X1104866Y1141674
X1104866Y1134981
X1121008Y1138327
X1121008Y1131634
X1104866Y1118248
X1104866Y1252107
X1104866Y1245414
X1104866Y1111555
X1121008Y1248760
X1121008Y1242067
X1104866Y1228681
X1104866Y1221988
X1121008Y1225335
X1121008Y1218642
X1104866Y1215296
X1104866Y1208603
X1121008Y1211949
X1121008Y1205256
X1121008Y1114902
X1104866Y1191870
X1104866Y1185177
X1121008Y1188524
X1121008Y1181831
X1104866Y1178485
X1104866Y1171792
X1121008Y1175138
X1121008Y1168445
X1104866Y1155059
X1104866Y1148366
X1121008Y1108209
X1104866Y1058012
X1121008Y1054666
X1104866Y1081437
X1104866Y1074744
X1121008Y1078091
X1121008Y1071398
X1104866Y1104862
X1104866Y1098170
X1121008Y1101516
X1121008Y1094823
X1121008Y1047973
X1104866Y1044626
X1121008Y1041280
X1104866Y1037933
X1121008Y1034587
X1104866Y1031240
X1121008Y1027894
X1121008Y1061359
X1121008Y1001122
X1104866Y0944233
X1104866Y0907422
X1104866Y0870610
R02Y-0036811
X1121008Y0937540
R04Y-0036811
X1104866Y0940886
R04Y-0036811
X1121008Y0940886
R04Y-0036811
X1121008Y0820414
X1121008Y0813721
X1104866Y0810374
X1104866Y0803681
X1121008Y0807028
X1121008Y0800335
X1104866Y0786949
X1104866Y0920807
X1104866Y0914114
X1104866Y0780256
X1121008Y0917461
X1121008Y0910768
X1104866Y0897382
X1104866Y0890689
X1121008Y0894036
X1121008Y0887343
X1104866Y0883996
X1104866Y0877303
X1121008Y0880650
X1121008Y0873957
X1121008Y0783603
X1104866Y0860571
X1104866Y0853878
X1121008Y0857225
X1121008Y0850532
X1104866Y0847185
X1104866Y0840492
X1121008Y0843839
X1121008Y0837146
X1104866Y0823760
X1104866Y0817067
X1121008Y0776910
X1104866Y0971004
X1121008Y0967658
X1104866Y0957618
X1104866Y0950925
X1121008Y0954272
X1121008Y0947579
X1104866Y0934193
X1104866Y0927500
X1121008Y0930847
X1121008Y0924154
X1121008Y0994429
X1104866Y0991083
X1121008Y0987736
X1104866Y0984390
X1121008Y0981044
X1104866Y0977697
X1121008Y0974351
X1104866Y0964311
X1104866Y0997776
X1104866Y1001122
X0160356Y0019541
X0153251Y0026477
X0124490Y0019541
X0117385Y0026477
X0110316Y0019541
X0103211Y0026477
X0096143Y0019541
X0089038Y0026477
X0081970Y0019541
X0218663Y0019541
X0211558Y0026477
X0204490Y0019541
X0197385Y0026477
X0174529Y0019541
X0167424Y0026477
X0074865Y0026477
X0163756Y0019541
X0156651Y0026477
X0127890Y0019541
X0120785Y0026477
X0113716Y0019541
X0106611Y0026477
X0099543Y0019541
X0092438Y0026477
X0085370Y0019541
X0222063Y0019541
X0214958Y0026477
X0207890Y0019541
X0200785Y0026477
X0177929Y0019541
X0170824Y0026477
X0078265Y0026477
X0653999Y1423357
X0653999Y1426757
X0691276Y1455112
X0694676Y1455112
M30
